#ISCELL
  mstr_misc dns *
  *
#ISCELL
  pure_quanta quanta_title_block_c *
  *
#CELL
  pure_quanta q_res *
  page273_i10
#ISCELL
  pure_quanta_power p1v0_aux *
  page273_i100
#ISCELL
  pure_quanta_power universal_gnd *
  page273_i101
#CELL
  pure_quanta q_res *
  page273_i102
#ISCELL
  pure_quanta_power universal_gnd *
  page273_i103
#CELL
  pure_quanta q_res *
  page273_i104
#ISCELL
  pure_quanta_power p1v0_aux *
  page273_i105
#ISCELL
  standard offpage *
  page273_i106
#CELL
  pure_quanta mosfet_nch_dual *
  page273_i107
#CELL
  pure_quanta mosfet_nch_dual *
  page273_i108
#ISCELL
  pure_quanta_power universal_gnd *
  page273_i109
#ISCELL
  pure_quanta_power universal_power *
  page273_i11
#ISCELL
  pure_quanta_power universal_gnd *
  page273_i110
#CELL
  pure_quanta q_res *
  page273_i111
#ISCELL
  pure_quanta_power universal_power *
  page273_i112
#CELL
  pure_quanta q_res *
  page273_i113
#CELL
  pure_quanta q_res *
  page273_i114
#ISCELL
  pure_quanta_power universal_power *
  page273_i115
#CELL
  pure_quanta q_cap *
  page273_i116
#ISCELL
  pure_quanta_power universal_gnd *
  page273_i117
#ISCELL
  standard offpage *
  page273_i12
#CELL
  pure_quanta q_res *
  page273_i120
#ISCELL
  pure_quanta_power universal_power *
  page273_i121
#ISCELL
  pure_quanta_power universal_gnd *
  page273_i122
#CELL
  pure_quanta bss138dw7f *
  page273_i123
#ISCELL
  pure_quanta_power universal_gnd *
  page273_i124
#CELL
  pure_quanta q_res *
  page273_i125
#ISCELL
  pure_quanta_power p1v0_aux *
  page273_i126
#ISCELL
  standard offpage *
  page273_i127
#ISCELL
  pure_quanta_power universal_gnd *
  page273_i13
#CELL
  pure_quanta q_res *
  page273_i130
#CELL
  pure_quanta apx80929sag7 *
  page273_i131
#ISCELL
  pure_quanta_power universal_power *
  page273_i132
#CELL
  pure_quanta q_cap *
  page273_i133
#ISCELL
  pure_quanta_power universal_gnd *
  page273_i134
#ISCELL
  pure_quanta_power universal_gnd *
  page273_i135
#CELL
  pure_quanta q_res *
  page273_i136
#ISCELL
  pure_quanta_power universal_power *
  page273_i138
#CELL
  pure_quanta q_res *
  page273_i139
#CELL
  pure_quanta mosfet_nch_dual *
  page273_i14
#ISCELL
  pure_quanta_power universal_gnd *
  page273_i140
#CELL
  pure_quanta q_res *
  page273_i141
#CELL
  pure_quanta q_res *
  page273_i15
#ISCELL
  pure_quanta_power universal_power *
  page273_i16
#ISCELL
  pure_quanta_power universal_gnd *
  page273_i17
#CELL
  pure_quanta q_cap *
  page273_i18
#CELL
  pure_quanta q_cap *
  page273_i19
#CELL
  pure_quanta q_cap *
  page273_i20
#ISCELL
  pure_quanta_power p1v0_aux *
  page273_i21
#CELL
  pure_quanta q_res *
  page273_i22
#CELL
  pure_quanta mosfet_nch_1d3s *
  page273_i23
#ISCELL
  pure_quanta_power universal_power *
  page273_i26
#CELL
  pure_quanta bat547f *
  page273_i27
#ISCELL
  pure_quanta_power universal_power *
  page273_i28
#ISCELL
  standard offpage *
  page273_i3
#ISCELL
  pure_quanta_power universal_gnd *
  page273_i37
#CELL
  pure_quanta q_cap *
  page273_i38
#ISCELL
  standard offpage *
  page273_i39
#CELL
  pure_quanta q_res *
  page273_i4
#ISCELL
  pure_quanta_power universal_gnd *
  page273_i40
#CELL
  pure_quanta q_cap *
  page273_i41
#ISCELL
  pure_quanta_power universal_power *
  page273_i42
#CELL
  pure_quanta q_cap *
  page273_i43
#ISCELL
  pure_quanta_power universal_gnd *
  page273_i44
#CELL
  pure_quanta q_res *
  page273_i45
#ISCELL
  pure_quanta_power universal_gnd *
  page273_i46
#CELL
  pure_quanta q_cap *
  page273_i48
#CELL
  pure_quanta q_cap *
  page273_i49
#CELL
  pure_quanta mosfet_nch_1d3s *
  page273_i50
#CELL
  pure_quanta q_cap *
  page273_i51
#ISCELL
  pure_quanta_power p1v0_aux *
  page273_i52
#ISCELL
  pure_quanta_power universal_gnd *
  page273_i58
#CELL
  pure_quanta q_cap *
  page273_i59
#ISCELL
  pure_quanta_power universal_gnd *
  page273_i6
#ISCELL
  pure_quanta_power universal_power *
  page273_i60
#CELL
  pure_quanta q_cap *
  page273_i61
#CELL
  pure_quanta mosfet_nch_gds_esd_protected *
  page273_i62
#CELL
  pure_quanta q_res *
  page273_i7
#CELL
  pure_quanta q_res *
  page273_i74
#CELL
  pure_quanta q_res *
  page273_i75
#CELL
  pure_quanta q_res *
  page273_i76
#CELL
  pure_quanta rt9818c44gv *
  page273_i77
#ISCELL
  pure_quanta_power universal_power *
  page273_i78
#CELL
  pure_quanta q_cap *
  page273_i79
#ISCELL
  pure_quanta_power universal_gnd *
  page273_i8
#ISCELL
  pure_quanta_power universal_gnd *
  page273_i80
#ISCELL
  pure_quanta_power universal_gnd *
  page273_i81
#CELL
  pure_quanta q_res *
  page273_i83
#CELL
  pure_quanta q_res *
  page273_i84
#ISCELL
  pure_quanta_power universal_power *
  page273_i85
#ISCELL
  pure_quanta_power universal_gnd *
  page273_i86
#CELL
  pure_quanta q_res *
  page273_i88
#CELL
  pure_quanta mosfet_nch_dual *
  page273_i9
#ISCELL
  standard offpage *
  page273_i90
#CELL
  pure_quanta q_res *
  page273_i91
#ISCELL
  pure_quanta_power universal_gnd *
  page273_i92
#CELL
  pure_quanta q_res *
  page273_i93
#ISCELL
  pure_quanta_power p1v0_aux *
  page273_i94
#CELL
  pure_quanta q_res *
  page273_i95
#CELL
  pure_quanta q_res *
  page273_i96
#CELL
  pure_quanta mosfet_nch_dual *
  page273_i97
#CELL
  pure_quanta mosfet_nch_dual *
  page273_i98
#CELL
  pure_quanta q_res *
  page273_i99
